(kicad_pcb
	(version 20260206)
	(generator "pcbnew")
	(generator_version "10.0")
	(general
		(thickness 1.6)
		(legacy_teardrops no)
	)
	(paper "A4")
	(title_block
		(title "Wiwynn_Tioga_Pass_MB.brd")
		(comment 1 "Tioga Pass / footprints 719-726 of 4770")
	)
	(layers
		(0 "F.Cu" signal "TOP")
		(4 "In1.Cu" signal "L2GND")
		(6 "In2.Cu" signal "L3")
		(8 "In3.Cu" signal "L4GND")
		(10 "In4.Cu" signal "L5")
		(12 "In5.Cu" signal "L6GND")
		(14 "In6.Cu" signal "L7VCC")
		(16 "In7.Cu" signal "L8VCC")
		(18 "In8.Cu" signal "L9GND")
		(20 "In9.Cu" signal "L10")
		(22 "In10.Cu" signal "L11GND")
		(24 "In11.Cu" signal "L12")
		(26 "In12.Cu" signal "L13GND")
		(2 "B.Cu" signal "BOTTOM")
		(9 "F.Adhes" user "F.Adhesive")
		(11 "B.Adhes" user "B.Adhesive")
		(13 "F.Paste" user "Package Geometry/Pastemask Top")
		(15 "B.Paste" user "Package Geometry/Pastemask Bottom")
		(5 "F.SilkS" user "Ref Des/Silkscreen Top")
		(7 "B.SilkS" user "Ref Des/Silkscreen Bottom")
		(1 "F.Mask" user "Board Geometry/Soldermask Top")
		(3 "B.Mask" user "Board Geometry/Soldermask Bottom")
		(17 "Dwgs.User" user "User.Drawings")
		(19 "Cmts.User" user "User.Comments")
		(21 "Eco1.User" user "User.Eco1")
		(23 "Eco2.User" user "User.Eco2")
		(25 "Edge.Cuts" user "Board Geometry/Outline")
		(27 "Margin" user)
		(31 "F.CrtYd" user "Package Geometry/Place Bound Top")
		(29 "B.CrtYd" user "Package Geometry/Place Bound Bottom")
		(35 "F.Fab" user "Ref Des/Assembly Top")
		(33 "B.Fab" user "Ref Des/Assembly Bottom")
	)
	(footprint ""
		(layer "F.Cu")
		(at 252.1585 -140.208 -90)
		(property "Reference" "C5A13"
			(at 1.848866 0.752348 270)
			(unlocked yes)
			(layer "F.SilkS")
			(effects
				(font
					(size 1.27 0.9652)
					(thickness 0.1524)
				)
			)
		)
		(property "Value" ""
			(at 0 0 270)
			(layer "F.Fab")
			(effects
				(font
					(size 1.27 1.27)
				)
			)
		)
		(duplicate_pad_numbers_are_jumpers no)
		(fp_rect
			(start -0.500126 1.598422)
			(end 0.500126 -0.201422)
			(stroke
				(width 0)
				(type default)
			)
			(fill no)
			(layer "F.CrtYd")
		)
		(fp_line
			(start -0.500126 1.598422)
			(end -0.500126 -0.201422)
			(stroke
				(width 0.1)
				(type default)
			)
			(layer "F.Fab")
		)
		(fp_line
			(start 0.500126 1.598422)
			(end -0.500126 1.598422)
			(stroke
				(width 0.1)
				(type default)
			)
			(layer "F.Fab")
		)
		(fp_line
			(start -0.500126 -0.201422)
			(end 0.500126 -0.201422)
			(stroke
				(width 0.1)
				(type default)
			)
			(layer "F.Fab")
		)
		(fp_line
			(start 0.500126 -0.201422)
			(end 0.500126 1.598422)
			(stroke
				(width 0.1)
				(type default)
			)
			(layer "F.Fab")
		)
		(pad "1" smd rect
			(at 0 0 180)
			(size 0.889 0.9906)
			(layers "F.Cu" "F.Mask" "F.Paste")
			(net "PVDDQ_DEF")
		)
		(pad "2" smd rect
			(at 0 1.397 180)
			(size 0.889 0.9906)
			(layers "F.Cu" "F.Mask" "F.Paste")
			(net "GND")
		)
		(zone
			(layer "F.Cu")
			(hatch none 0.5)
			(connect_pads
				(clearance 0)
			)
			(min_thickness 0.25)
			(keepout
				(tracks not_allowed)
				(vias allowed)
				(pads allowed)
				(copperpour not_allowed)
				(footprints allowed)
			)
			(placement
				(enabled no)
				(sheetname "")
			)
			(fill
				(thermal_gap 0.5)
				(thermal_bridge_width 0.5)
				(island_removal_mode 0)
			)
			(polygon
				(pts
					(xy 251.206 -140.7033) (xy 251.206 -139.7127) (xy 251.714 -139.7127) (xy 251.714 -140.7033)
				)
			)
		)
		(zone
			(layer "F.Cu")
			(hatch none 0.5)
			(connect_pads
				(clearance 0)
			)
			(min_thickness 0.25)
			(keepout
				(tracks allowed)
				(vias not_allowed)
				(pads allowed)
				(copperpour not_allowed)
				(footprints allowed)
			)
			(placement
				(enabled no)
				(sheetname "")
			)
			(fill
				(thermal_gap 0.5)
				(thermal_bridge_width 0.5)
				(island_removal_mode 0)
			)
			(polygon
				(pts
					(xy 251.206 -140.7033) (xy 251.206 -139.7127) (xy 251.714 -139.7127) (xy 251.714 -140.7033)
				)
			)
		)
	)
	(footprint ""
		(layer "F.Cu")
		(at 194.564 -22.507194 180)
		(property "Reference" "R4F5"
			(at 0 0 180)
			(layer "F.SilkS")
			(hide yes)
			(effects
				(font
					(size 1.27 1.27)
				)
			)
		)
		(property "Value" ""
			(at 0 0 180)
			(layer "F.Fab")
			(effects
				(font
					(size 1.27 1.27)
				)
			)
		)
		(duplicate_pad_numbers_are_jumpers no)
		(fp_poly
			(pts
				(xy -0.2794 -0.1016) (xy 0.2794 -0.1016) (xy 0.2794 0.9906) (xy -0.2794 0.9906)
			)
			(stroke
				(width 0)
				(type default)
			)
			(fill no)
			(layer "F.CrtYd")
		)
		(fp_line
			(start 0.2794 0.9906)
			(end 0.2794 -0.1016)
			(stroke
				(width 0.1)
				(type default)
			)
			(layer "F.Fab")
		)
		(fp_line
			(start 0.2794 -0.1016)
			(end -0.2794 -0.1016)
			(stroke
				(width 0.1)
				(type default)
			)
			(layer "F.Fab")
		)
		(fp_line
			(start -0.2794 0.9906)
			(end 0.2794 0.9906)
			(stroke
				(width 0.1)
				(type default)
			)
			(layer "F.Fab")
		)
		(fp_line
			(start -0.2794 -0.1016)
			(end -0.2794 0.9906)
			(stroke
				(width 0.1)
				(type default)
			)
			(layer "F.Fab")
		)
		(pad "1" smd rect
			(at 0 0 180)
			(size 0.508 0.508)
			(layers "F.Cu" "F.Mask" "F.Paste")
			(net "M_A_VREF")
		)
		(pad "2" smd rect
			(at 0 0.889 180)
			(size 0.508 0.508)
			(layers "F.Cu" "F.Mask" "F.Paste")
			(net "GND")
		)
		(zone
			(layer "F.Cu")
			(hatch none 0.5)
			(connect_pads
				(clearance 0)
			)
			(min_thickness 0.25)
			(keepout
				(tracks not_allowed)
				(vias allowed)
				(pads allowed)
				(copperpour not_allowed)
				(footprints allowed)
			)
			(placement
				(enabled no)
				(sheetname "")
			)
			(fill
				(thermal_gap 0.5)
				(thermal_bridge_width 0.5)
				(island_removal_mode 0)
			)
			(polygon
				(pts
					(xy 194.818 -23.142194) (xy 194.31 -23.142194) (xy 194.31 -22.761194) (xy 194.818 -22.761194)
				)
			)
		)
		(zone
			(layer "F.Cu")
			(hatch none 0.5)
			(connect_pads
				(clearance 0)
			)
			(min_thickness 0.25)
			(keepout
				(tracks allowed)
				(vias not_allowed)
				(pads allowed)
				(copperpour not_allowed)
				(footprints allowed)
			)
			(placement
				(enabled no)
				(sheetname "")
			)
			(fill
				(thermal_gap 0.5)
				(thermal_bridge_width 0.5)
				(island_removal_mode 0)
			)
			(polygon
				(pts
					(xy 194.818 -22.761194) (xy 194.31 -22.761194) (xy 194.31 -23.142194) (xy 194.818 -23.142194)
				)
			)
		)
	)
	(footprint ""
		(layer "F.Cu")
		(at 411.086046 -22.196552)
		(property "Reference" "C25W7"
			(at -0.8382 -0.67818 0)
			(unlocked yes)
			(layer "F.SilkS")
			(effects
				(font
					(size 0.4064 0.254)
					(thickness 0.1524)
				)
				(justify left)
			)
		)
		(property "Value" ""
			(at 0 0 0)
			(layer "F.Fab")
			(effects
				(font
					(size 1.27 1.27)
				)
			)
		)
		(duplicate_pad_numbers_are_jumpers no)
		(fp_poly
			(pts
				(xy 0.3048 -0.1016) (xy 0.3048 0.9906) (xy -0.3048 0.9906) (xy -0.3048 -0.1016)
			)
			(stroke
				(width 0)
				(type default)
			)
			(fill no)
			(layer "F.CrtYd")
		)
		(fp_line
			(start -0.3048 -0.1016)
			(end -0.3048 0.9906)
			(stroke
				(width 0.1)
				(type default)
			)
			(layer "F.Fab")
		)
		(fp_line
			(start -0.3048 0.9906)
			(end 0.3048 0.9906)
			(stroke
				(width 0.1)
				(type default)
			)
			(layer "F.Fab")
		)
		(fp_line
			(start 0.3048 -0.1016)
			(end -0.3048 -0.1016)
			(stroke
				(width 0.1)
				(type default)
			)
			(layer "F.Fab")
		)
		(fp_line
			(start 0.3048 0.9906)
			(end 0.3048 -0.1016)
			(stroke
				(width 0.1)
				(type default)
			)
			(layer "F.Fab")
		)
		(pad "1" smd rect
			(at 0 0)
			(size 0.508 0.508)
			(layers "F.Cu" "F.Mask" "F.Paste")
			(net "P3V3_STBY_BMC_ADCVREFP")
		)
		(pad "2" smd rect
			(at 0 0.889)
			(size 0.508 0.508)
			(layers "F.Cu" "F.Mask" "F.Paste")
			(net "VCC_ADCAV3V3")
		)
		(zone
			(layer "F.Cu")
			(hatch none 0.5)
			(connect_pads
				(clearance 0)
			)
			(min_thickness 0.25)
			(keepout
				(tracks allowed)
				(vias not_allowed)
				(pads allowed)
				(copperpour not_allowed)
				(footprints allowed)
			)
			(placement
				(enabled no)
				(sheetname "")
			)
			(fill
				(thermal_gap 0.5)
				(thermal_bridge_width 0.5)
				(island_removal_mode 0)
			)
			(polygon
				(pts
					(xy 410.832046 -21.942552) (xy 411.340046 -21.942552) (xy 411.340046 -21.561552) (xy 410.832046 -21.561552)
				)
			)
		)
		(zone
			(layer "F.Cu")
			(hatch none 0.5)
			(connect_pads
				(clearance 0)
			)
			(min_thickness 0.25)
			(keepout
				(tracks not_allowed)
				(vias allowed)
				(pads allowed)
				(copperpour not_allowed)
				(footprints allowed)
			)
			(placement
				(enabled no)
				(sheetname "")
			)
			(fill
				(thermal_gap 0.5)
				(thermal_bridge_width 0.5)
				(island_removal_mode 0)
			)
			(polygon
				(pts
					(xy 410.832046 -21.561552) (xy 411.340046 -21.561552) (xy 411.340046 -21.942552) (xy 410.832046 -21.942552)
				)
			)
		)
	)
	(footprint ""
		(layer "F.Cu")
		(at 264.453624 -69.885814 -90)
		(property "Reference" "C5D54"
			(at 0 0 270)
			(layer "F.SilkS")
			(hide yes)
			(effects
				(font
					(size 1.27 1.27)
				)
			)
		)
		(property "Value" ""
			(at 0 0 270)
			(layer "F.Fab")
			(effects
				(font
					(size 1.27 1.27)
				)
			)
		)
		(duplicate_pad_numbers_are_jumpers no)
		(fp_poly
			(pts
				(xy -0.4953 -0.2032) (xy 0.4953 -0.2032) (xy 0.4953 1.6002) (xy -0.4953 1.6002)
			)
			(stroke
				(width 0)
				(type default)
			)
			(fill no)
			(layer "F.CrtYd")
		)
		(fp_line
			(start -0.4953 1.6002)
			(end -0.4953 -0.2032)
			(stroke
				(width 0.1)
				(type default)
			)
			(layer "F.Fab")
		)
		(fp_line
			(start 0.4953 1.6002)
			(end -0.4953 1.6002)
			(stroke
				(width 0.1)
				(type default)
			)
			(layer "F.Fab")
		)
		(fp_line
			(start -0.4953 -0.2032)
			(end 0.4953 -0.2032)
			(stroke
				(width 0.1)
				(type default)
			)
			(layer "F.Fab")
		)
		(fp_line
			(start 0.4953 -0.2032)
			(end 0.4953 1.6002)
			(stroke
				(width 0.1)
				(type default)
			)
			(layer "F.Fab")
		)
		(pad "1" smd rect
			(at 0 0 270)
			(size 0.762 0.889)
			(layers "F.Cu" "F.Mask" "F.Paste")
			(net "PVDDQ_ABC")
		)
		(pad "2" smd rect
			(at 0 1.397 270)
			(size 0.762 0.889)
			(layers "F.Cu" "F.Mask" "F.Paste")
			(net "GND")
		)
		(zone
			(layer "F.Cu")
			(hatch none 0.5)
			(connect_pads
				(clearance 0)
			)
			(min_thickness 0.25)
			(keepout
				(tracks not_allowed)
				(vias allowed)
				(pads allowed)
				(copperpour not_allowed)
				(footprints allowed)
			)
			(placement
				(enabled no)
				(sheetname "")
			)
			(fill
				(thermal_gap 0.5)
				(thermal_bridge_width 0.5)
				(island_removal_mode 0)
			)
			(polygon
				(pts
					(xy 264.009124 -70.266814) (xy 264.009124 -69.504814) (xy 263.501124 -69.504814) (xy 263.501124 -70.266814)
				)
			)
		)
	)
	(footprint ""
		(layer "F.Cu")
		(at 401.8915 -37.9984 90)
		(property "Reference" "R1L7"
			(at 0 0 90)
			(layer "F.SilkS")
			(hide yes)
			(effects
				(font
					(size 1.27 1.27)
				)
			)
		)
		(property "Value" ""
			(at 0 0 90)
			(layer "F.Fab")
			(effects
				(font
					(size 1.27 1.27)
				)
			)
		)
		(duplicate_pad_numbers_are_jumpers no)
		(fp_poly
			(pts
				(xy -0.2794 -0.1016) (xy 0.2794 -0.1016) (xy 0.2794 0.9906) (xy -0.2794 0.9906)
			)
			(stroke
				(width 0)
				(type default)
			)
			(fill no)
			(layer "F.CrtYd")
		)
		(fp_line
			(start 0.2794 -0.1016)
			(end -0.2794 -0.1016)
			(stroke
				(width 0.1)
				(type default)
			)
			(layer "F.Fab")
		)
		(fp_line
			(start -0.2794 -0.1016)
			(end -0.2794 0.9906)
			(stroke
				(width 0.1)
				(type default)
			)
			(layer "F.Fab")
		)
		(fp_line
			(start 0.2794 0.9906)
			(end 0.2794 -0.1016)
			(stroke
				(width 0.1)
				(type default)
			)
			(layer "F.Fab")
		)
		(fp_line
			(start -0.2794 0.9906)
			(end 0.2794 0.9906)
			(stroke
				(width 0.1)
				(type default)
			)
			(layer "F.Fab")
		)
		(pad "1" smd rect
			(at 0 0 90)
			(size 0.508 0.508)
			(layers "F.Cu" "F.Mask" "F.Paste")
			(net "P3V3_STBY")
		)
		(pad "2" smd rect
			(at 0 0.889 90)
			(size 0.508 0.508)
			(layers "F.Cu" "F.Mask" "F.Paste")
			(net "FM_BMC_CPLD_MP_RST_N")
		)
		(zone
			(layer "F.Cu")
			(hatch none 0.5)
			(connect_pads
				(clearance 0)
			)
			(min_thickness 0.25)
			(keepout
				(tracks allowed)
				(vias not_allowed)
				(pads allowed)
				(copperpour not_allowed)
				(footprints allowed)
			)
			(placement
				(enabled no)
				(sheetname "")
			)
			(fill
				(thermal_gap 0.5)
				(thermal_bridge_width 0.5)
				(island_removal_mode 0)
			)
			(polygon
				(pts
					(xy 402.1455 -37.7444) (xy 402.1455 -38.2524) (xy 402.5265 -38.2524) (xy 402.5265 -37.7444)
				)
			)
		)
		(zone
			(layer "F.Cu")
			(hatch none 0.5)
			(connect_pads
				(clearance 0)
			)
			(min_thickness 0.25)
			(keepout
				(tracks not_allowed)
				(vias allowed)
				(pads allowed)
				(copperpour not_allowed)
				(footprints allowed)
			)
			(placement
				(enabled no)
				(sheetname "")
			)
			(fill
				(thermal_gap 0.5)
				(thermal_bridge_width 0.5)
				(island_removal_mode 0)
			)
			(polygon
				(pts
					(xy 402.5265 -37.7444) (xy 402.5265 -38.2524) (xy 402.1455 -38.2524) (xy 402.1455 -37.7444)
				)
			)
		)
	)
	(footprint ""
		(layer "F.Cu")
		(at 365.5568 -134.8994 180)
		(property "Reference" "R7A9"
			(at -0.8382 -0.67818 180)
			(unlocked yes)
			(layer "F.SilkS")
			(effects
				(font
					(size 0.4064 0.254)
					(thickness 0.1524)
				)
				(justify left)
			)
		)
		(property "Value" ""
			(at 0 0 180)
			(layer "F.Fab")
			(effects
				(font
					(size 1.27 1.27)
				)
			)
		)
		(duplicate_pad_numbers_are_jumpers no)
		(fp_poly
			(pts
				(xy -0.2794 -0.1016) (xy 0.2794 -0.1016) (xy 0.2794 0.9906) (xy -0.2794 0.9906)
			)
			(stroke
				(width 0)
				(type default)
			)
			(fill no)
			(layer "F.CrtYd")
		)
		(fp_line
			(start 0.2794 0.9906)
			(end 0.2794 -0.1016)
			(stroke
				(width 0.1)
				(type default)
			)
			(layer "F.Fab")
		)
		(fp_line
			(start 0.2794 -0.1016)
			(end -0.2794 -0.1016)
			(stroke
				(width 0.1)
				(type default)
			)
			(layer "F.Fab")
		)
		(fp_line
			(start -0.2794 0.9906)
			(end 0.2794 0.9906)
			(stroke
				(width 0.1)
				(type default)
			)
			(layer "F.Fab")
		)
		(fp_line
			(start -0.2794 -0.1016)
			(end -0.2794 0.9906)
			(stroke
				(width 0.1)
				(type default)
			)
			(layer "F.Fab")
		)
		(pad "1" smd rect
			(at 0 0 180)
			(size 0.508 0.508)
			(layers "F.Cu" "F.Mask" "F.Paste")
			(net "P3V3_STBY")
		)
		(pad "2" smd rect
			(at 0 0.889 180)
			(size 0.508 0.508)
			(layers "F.Cu" "F.Mask" "F.Paste")
			(net "PWRGD_PVDDQ_DEF")
		)
		(zone
			(layer "F.Cu")
			(hatch none 0.5)
			(connect_pads
				(clearance 0)
			)
			(min_thickness 0.25)
			(keepout
				(tracks not_allowed)
				(vias allowed)
				(pads allowed)
				(copperpour not_allowed)
				(footprints allowed)
			)
			(placement
				(enabled no)
				(sheetname "")
			)
			(fill
				(thermal_gap 0.5)
				(thermal_bridge_width 0.5)
				(island_removal_mode 0)
			)
			(polygon
				(pts
					(xy 365.8108 -135.5344) (xy 365.3028 -135.5344) (xy 365.3028 -135.1534) (xy 365.8108 -135.1534)
				)
			)
		)
		(zone
			(layer "F.Cu")
			(hatch none 0.5)
			(connect_pads
				(clearance 0)
			)
			(min_thickness 0.25)
			(keepout
				(tracks allowed)
				(vias not_allowed)
				(pads allowed)
				(copperpour not_allowed)
				(footprints allowed)
			)
			(placement
				(enabled no)
				(sheetname "")
			)
			(fill
				(thermal_gap 0.5)
				(thermal_bridge_width 0.5)
				(island_removal_mode 0)
			)
			(polygon
				(pts
					(xy 365.8108 -135.1534) (xy 365.3028 -135.1534) (xy 365.3028 -135.5344) (xy 365.8108 -135.5344)
				)
			)
		)
	)
	(footprint ""
		(layer "F.Cu")
		(at 386.464302 -83.223608)
		(property "Reference" "U14E3"
			(at -0.14986 2.621788 0)
			(unlocked yes)
			(layer "F.SilkS")
			(effects
				(font
					(size 1.27 0.964946)
					(thickness 0.000001)
				)
				(justify left)
			)
		)
		(property "Value" ""
			(at 0 0 0)
			(layer "F.Fab")
			(effects
				(font
					(size 1.27 1.27)
				)
			)
		)
		(duplicate_pad_numbers_are_jumpers no)
		(fp_circle
			(center -0.4699 -0.8382)
			(end -0.3429 -0.8382)
			(stroke
				(width 0.254)
				(type default)
			)
			(fill no)
			(layer "F.SilkS")
		)
		(fp_poly
			(pts
				(xy 0.21463 -0.450088) (xy 1.56337 -0.450088) (xy 1.56337 1.75006) (xy 0.21463 1.75006)
			)
			(stroke
				(width 0)
				(type default)
			)
			(fill no)
			(layer "F.CrtYd")
		)
		(fp_line
			(start 0.21463 -0.450088)
			(end 1.56337 -0.450088)
			(stroke
				(width 0.1)
				(type default)
			)
			(layer "F.Fab")
		)
		(fp_line
			(start 0.21463 1.75006)
			(end 0.21463 -0.450088)
			(stroke
				(width 0.1)
				(type default)
			)
			(layer "F.Fab")
		)
		(fp_line
			(start 1.56337 -0.450088)
			(end 1.56337 1.75006)
			(stroke
				(width 0.1)
				(type default)
			)
			(layer "F.Fab")
		)
		(fp_line
			(start 1.56337 1.75006)
			(end 0.21463 1.75006)
			(stroke
				(width 0.1)
				(type default)
			)
			(layer "F.Fab")
		)
		(fp_circle
			(center -0.4699 -0.8382)
			(end -0.3429 -0.8382)
			(stroke
				(width 0.254)
				(type default)
			)
			(fill no)
			(layer "F.Fab")
		)
		(pad "1" smd rect
			(at 0 0)
			(size 1.016 0.381)
			(layers "F.Cu" "F.Mask" "F.Paste")
			(net "PWRGD_P12V_HSC_DLY")
		)
		(pad "2" smd rect
			(at 0 0.649986)
			(size 1.016 0.381)
			(layers "F.Cu" "F.Mask" "F.Paste")
			(net "PWRGD_P3V3")
		)
		(pad "3" smd rect
			(at 0 1.299972)
			(size 1.016 0.381)
			(layers "F.Cu" "F.Mask" "F.Paste")
			(net "GND")
		)
		(pad "4" smd rect
			(at 1.778 1.299972)
			(size 1.016 0.381)
			(layers "F.Cu" "F.Mask" "F.Paste")
			(net "RST_PCIE_M2_DEV_AND")
		)
		(pad "5" smd rect
			(at 1.778 0)
			(size 1.016 0.381)
			(layers "F.Cu" "F.Mask" "F.Paste")
			(net "P3V3")
		)
	)
	(footprint ""
		(layer "F.Cu")
		(at 478.30486 -18.48739)
		(property "Reference" "C9G4"
			(at 0 0 0)
			(layer "F.SilkS")
			(hide yes)
			(effects
				(font
					(size 1.27 1.27)
				)
			)
		)
		(property "Value" ""
			(at 0 0 0)
			(layer "F.Fab")
			(effects
				(font
					(size 1.27 1.27)
				)
			)
		)
		(duplicate_pad_numbers_are_jumpers no)
		(fp_poly
			(pts
				(xy 0.3048 -0.1016) (xy 0.3048 0.9906) (xy -0.3048 0.9906) (xy -0.3048 -0.1016)
			)
			(stroke
				(width 0)
				(type default)
			)
			(fill no)
			(layer "F.CrtYd")
		)
		(fp_line
			(start -0.3048 -0.1016)
			(end -0.3048 0.9906)
			(stroke
				(width 0.1)
				(type default)
			)
			(layer "F.Fab")
		)
		(fp_line
			(start -0.3048 0.9906)
			(end 0.3048 0.9906)
			(stroke
				(width 0.1)
				(type default)
			)
			(layer "F.Fab")
		)
		(fp_line
			(start 0.3048 -0.1016)
			(end -0.3048 -0.1016)
			(stroke
				(width 0.1)
				(type default)
			)
			(layer "F.Fab")
		)
		(fp_line
			(start 0.3048 0.9906)
			(end 0.3048 -0.1016)
			(stroke
				(width 0.1)
				(type default)
			)
			(layer "F.Fab")
		)
		(pad "1" smd rect
			(at 0 0)
			(size 0.508 0.508)
			(layers "F.Cu" "F.Mask" "F.Paste")
			(net "GND_LAN_TRCT1234_C")
		)
		(pad "2" smd rect
			(at 0 0.889)
			(size 0.508 0.508)
			(layers "F.Cu" "F.Mask" "F.Paste")
			(net "GND")
		)
		(zone
			(layer "F.Cu")
			(hatch none 0.5)
			(connect_pads
				(clearance 0)
			)
			(min_thickness 0.25)
			(keepout
				(tracks allowed)
				(vias not_allowed)
				(pads allowed)
				(copperpour not_allowed)
				(footprints allowed)
			)
			(placement
				(enabled no)
				(sheetname "")
			)
			(fill
				(thermal_gap 0.5)
				(thermal_bridge_width 0.5)
				(island_removal_mode 0)
			)
			(polygon
				(pts
					(xy 478.05086 -18.23339) (xy 478.55886 -18.23339) (xy 478.55886 -17.85239) (xy 478.05086 -17.85239)
				)
			)
		)
		(zone
			(layer "F.Cu")
			(hatch none 0.5)
			(connect_pads
				(clearance 0)
			)
			(min_thickness 0.25)
			(keepout
				(tracks not_allowed)
				(vias allowed)
				(pads allowed)
				(copperpour not_allowed)
				(footprints allowed)
			)
			(placement
				(enabled no)
				(sheetname "")
			)
			(fill
				(thermal_gap 0.5)
				(thermal_bridge_width 0.5)
				(island_removal_mode 0)
			)
			(polygon
				(pts
					(xy 478.05086 -17.85239) (xy 478.55886 -17.85239) (xy 478.55886 -18.23339) (xy 478.05086 -18.23339)
				)
			)
		)
	)
)
